(kicad_pcb
	(version 20260206)
	(generator "pcbnew")
	(generator_version "10.0")
	(general
		(thickness 1.6)
		(legacy_teardrops no)
	)
	(paper "A4")
	(title_block
		(title "dpb — 14545-sa.0730WZS0815.brd")
		(comment 1 "Honey Badger (Wiwynn) / footprints 291-293 of 1066")
	)
	(layers
		(0 "F.Cu" signal "TOP")
		(4 "In1.Cu" signal "L2GND")
		(6 "In2.Cu" signal "L3")
		(8 "In3.Cu" signal "L4VCC")
		(10 "In4.Cu" signal "L5VCC")
		(12 "In5.Cu" signal "L6")
		(14 "In6.Cu" signal "L7GND")
		(2 "B.Cu" signal "BOTTOM")
		(9 "F.Adhes" user "F.Adhesive")
		(11 "B.Adhes" user "B.Adhesive")
		(13 "F.Paste" user "Package Geometry/Pastemask Top")
		(15 "B.Paste" user "Package Geometry/Pastemask Bottom")
		(5 "F.SilkS" user "Ref Des/Silkscreen Top")
		(7 "B.SilkS" user "Ref Des/Silkscreen Bottom")
		(1 "F.Mask" user "Board Geometry/Soldermask Top")
		(3 "B.Mask" user "Board Geometry/Soldermask Bottom")
		(17 "Dwgs.User" user "User.Drawings")
		(19 "Cmts.User" user "User.Comments")
		(21 "Eco1.User" user "User.Eco1")
		(23 "Eco2.User" user "User.Eco2")
		(25 "Edge.Cuts" user "Board Geometry/Outline")
		(27 "Margin" user)
		(31 "F.CrtYd" user "Package Geometry/Place Bound Top")
		(29 "B.CrtYd" user "Package Geometry/Place Bound Bottom")
		(35 "F.Fab" user "Ref Des/Assembly Top")
		(33 "B.Fab" user "Ref Des/Assembly Bottom")
	)
	(footprint ""
		(layer "F.Cu")
		(at 2.500122 -460.004668 -90)
		(property "Reference" "CN5"
			(at 0 0 270)
			(layer "F.SilkS")
			(hide yes)
			(effects
				(font
					(size 1.27 1.27)
				)
			)
		)
		(property "Value" "PCISLT36-27-GP"
			(at 5.281422 -7.491476 270)
			(unlocked yes)
			(layer "F.Fab")
			(hide yes)
			(effects
				(font
					(size 1.016 1.016)
					(thickness 0.1524)
				)
			)
		)
		(property "Device Type" "G630H3612248EU"
			(at 5.281422 -9.015476 270)
			(unlocked yes)
			(layer "F.Fab")
			(hide yes)
			(effects
				(font
					(size 1.016 1.016)
					(thickness 0.1524)
				)
			)
		)
		(duplicate_pad_numbers_are_jumpers no)
		(fp_line
			(start -14.899894 2.499868)
			(end -1.450086 2.499868)
			(stroke
				(width 0.1524)
				(type default)
			)
			(layer "F.SilkS")
		)
		(fp_line
			(start -1.450086 2.499868)
			(end -0.94996 1.999742)
			(stroke
				(width 0.1524)
				(type default)
			)
			(layer "F.SilkS")
		)
		(fp_line
			(start 1.450086 2.499868)
			(end 18.899886 2.499868)
			(stroke
				(width 0.1524)
				(type default)
			)
			(layer "F.SilkS")
		)
		(fp_line
			(start 18.899886 2.499868)
			(end 19.400012 1.999742)
			(stroke
				(width 0.1524)
				(type default)
			)
			(layer "F.SilkS")
		)
		(fp_line
			(start -15.40002 1.999742)
			(end -14.899894 2.499868)
			(stroke
				(width 0.1524)
				(type default)
			)
			(layer "F.SilkS")
		)
		(fp_line
			(start -0.94996 1.999742)
			(end -0.94996 -2.55016)
			(stroke
				(width 0.1524)
				(type default)
			)
			(layer "F.SilkS")
		)
		(fp_line
			(start 0.94996 1.999742)
			(end 1.450086 2.499868)
			(stroke
				(width 0.1524)
				(type default)
			)
			(layer "F.SilkS")
		)
		(fp_line
			(start 19.400012 1.999742)
			(end 19.400012 -4.064)
			(stroke
				(width 0.1524)
				(type default)
			)
			(layer "F.SilkS")
		)
		(fp_line
			(start 0.94996 -2.539746)
			(end 0.94996 1.999742)
			(stroke
				(width 0.1524)
				(type default)
			)
			(layer "F.SilkS")
		)
		(fp_line
			(start 0.94996 -2.55016)
			(end 0.94996 -2.539746)
			(stroke
				(width 0.1524)
				(type default)
			)
			(layer "F.SilkS")
		)
		(fp_line
			(start -15.40002 -4.064)
			(end -15.40002 1.999742)
			(stroke
				(width 0.1524)
				(type default)
			)
			(layer "F.SilkS")
		)
		(fp_line
			(start 19.400012 -4.064)
			(end -15.40002 -4.064)
			(stroke
				(width 0.1524)
				(type default)
			)
			(layer "F.SilkS")
		)
		(fp_line
			(start 11.6713 -4.1529)
			(end 11.2903 -4.1529)
			(stroke
				(width 0.3302)
				(type default)
			)
			(layer "F.SilkS")
		)
		(fp_arc
			(start -0.94996 -2.55016)
			(mid 0 -3.50012)
			(end 0.94996 -2.55016)
			(stroke
				(width 0.1524)
				(type default)
			)
			(layer "F.SilkS")
		)
		(fp_poly
			(pts
				(xy 11.474704 -4.1402) (xy 10.966704 -4.6482) (xy 11.982704 -4.6482)
			)
			(stroke
				(width 0)
				(type default)
			)
			(fill yes)
			(layer "F.SilkS")
		)
		(fp_poly
			(pts
				(xy -10.4902 14.986) (xy -10.4902 4.8006) (xy -15.3924 4.8006) (xy -15.3924 -3.81) (xy 19.4056 -3.81)
				(xy 19.4056 4.8006) (xy 14.5034 4.8006) (xy 14.5034 14.986)
			)
			(stroke
				(width 0)
				(type default)
			)
			(fill no)
			(layer "B.CrtYd")
		)
		(fp_poly
			(pts
				(xy -10.9982 15.494) (xy -10.9982 5.3086) (xy -15.9004 5.3086) (xy -15.9004 -4.318) (xy 19.9136 -4.318)
				(xy 19.9136 5.3086) (xy 15.0114 5.3086) (xy 15.0114 15.494) (xy 0.00254 15.494) (xy 0.00254 14.986)
				(xy 14.5034 14.986) (xy 14.5034 4.8006) (xy 19.4056 4.8006) (xy 19.4056 -3.81) (xy -15.3924 -3.81)
				(xy -15.3924 4.8006) (xy -10.4902 4.8006) (xy -10.4902 14.986) (xy -0.00254 14.986) (xy -0.00254 15.494)
			)
			(stroke
				(width 0)
				(type default)
			)
			(fill no)
			(layer "B.CrtYd")
		)
		(fp_poly
			(pts
				(xy -10.4902 14.986) (xy -10.4902 4.8006) (xy -15.3924 4.8006) (xy -15.3924 -3.81) (xy 19.4056 -3.81)
				(xy 19.4056 4.8006) (xy 14.5034 4.8006) (xy 14.5034 14.986)
			)
			(stroke
				(width 0)
				(type default)
			)
			(fill no)
			(layer "F.CrtYd")
		)
		(fp_poly
			(pts
				(xy -10.9982 15.494) (xy -10.9982 5.3086) (xy -15.9004 5.3086) (xy -15.9004 -4.318) (xy 19.9136 -4.318)
				(xy 19.9136 5.3086) (xy 15.0114 5.3086) (xy 15.0114 15.494) (xy 0.00254 15.494) (xy 0.00254 14.986)
				(xy 14.5034 14.986) (xy 14.5034 4.8006) (xy 19.4056 4.8006) (xy 19.4056 -3.81) (xy -15.3924 -3.81)
				(xy -15.3924 4.8006) (xy -10.4902 4.8006) (xy -10.4902 14.986) (xy -0.00254 14.986) (xy -0.00254 15.494)
			)
			(stroke
				(width 0)
				(type default)
			)
			(fill no)
			(layer "F.CrtYd")
		)
		(fp_poly
			(pts
				(xy -10.9982 15.494) (xy -10.9982 5.3086) (xy -15.9004 5.3086) (xy -15.9004 -4.318) (xy 19.9136 -4.318)
				(xy 19.9136 5.3086) (xy 15.0114 5.3086) (xy 15.0114 15.494)
			)
			(stroke
				(width 0)
				(type default)
			)
			(fill no)
			(layer "B.Fab")
		)
		(fp_poly
			(pts
				(xy -10.9982 15.494) (xy -10.9982 5.3086) (xy -15.9004 5.3086) (xy -15.9004 -4.318) (xy 19.9136 -4.318)
				(xy 19.9136 5.3086) (xy 15.0114 5.3086) (xy 15.0114 15.494)
			)
			(stroke
				(width 0)
				(type default)
			)
			(fill no)
			(layer "F.Fab")
		)
		(fp_text user "Slit"
			(at 1.9304 5.260086 270)
			(unlocked yes)
			(layer "F.SilkS")
			(effects
				(font
					(size 0.635 0.635)
					(thickness 0.1524)
				)
				(justify left)
			)
		)
		(pad "" np_thru_hole circle
			(at -12.300204 0 270)
			(size 0.254 0.254)
			(drill 2.3114)
			(layers "*.Cu" "*.Mask")
			(clearance 1.3843)
			(thermal_gap 1.3843)
		)
		(pad "" np_thru_hole circle
			(at 16.299942 0 270)
			(size 0.254 0.254)
			(drill 2.3114)
			(layers "*.Cu" "*.Mask")
			(clearance 1.3843)
			(thermal_gap 1.3843)
		)
		(pad "A1" smd rect
			(at 11.500104 -0.309118 270)
			(size 0.7112 3.6068)
			(drill
				(offset 0 -0.381)
			)
			(layers "F.Cu" "F.Mask" "F.Paste")
			(net "HDD_PRSNT11")
		)
		(pad "A2" smd rect
			(at 10.500106 -0.309118 270)
			(size 0.7112 3.6068)
			(drill
				(offset 0 -0.381)
			)
			(layers "F.Cu" "F.Mask" "F.Paste")
			(net "HDD_PRSNT12")
		)
		(pad "A3" smd rect
			(at 9.500108 -0.309118 270)
			(size 0.7112 3.6068)
			(drill
				(offset 0 -0.381)
			)
			(layers "F.Cu" "F.Mask" "F.Paste")
			(net "HDD_PRSNT13")
		)
		(pad "A4" smd rect
			(at 8.50011 -0.309118 270)
			(size 0.7112 3.6068)
			(drill
				(offset 0 -0.381)
			)
			(layers "F.Cu" "F.Mask" "F.Paste")
			(net "HDD_PRSNT14")
		)
		(pad "A5" smd rect
			(at 7.500112 -0.309118 270)
			(size 0.7112 3.6068)
			(drill
				(offset 0 -0.381)
			)
			(layers "F.Cu" "F.Mask" "F.Paste")
			(net "HDD_PRSNT9")
		)
		(pad "A6" smd rect
			(at 6.500114 -0.309118 270)
			(size 0.7112 3.6068)
			(drill
				(offset 0 -0.381)
			)
			(layers "F.Cu" "F.Mask" "F.Paste")
			(net "HDD_PRSNT8")
		)
		(pad "A7" smd rect
			(at 5.500116 -0.309118 270)
			(size 0.7112 3.6068)
			(drill
				(offset 0 -0.381)
			)
			(layers "F.Cu" "F.Mask" "F.Paste")
			(net "HDD_PRSNT7")
		)
		(pad "A8" smd rect
			(at 4.500118 -0.309118 270)
			(size 0.7112 3.6068)
			(drill
				(offset 0 -0.381)
			)
			(layers "F.Cu" "F.Mask" "F.Paste")
			(net "HDD_PRSNT4")
		)
		(pad "A9" smd rect
			(at 3.50012 -0.309118 270)
			(size 0.7112 3.6068)
			(drill
				(offset 0 -0.381)
			)
			(layers "F.Cu" "F.Mask" "F.Paste")
			(net "HDD_PRSNT3")
		)
		(pad "A10" smd rect
			(at 2.500122 -0.309118 270)
			(size 0.7112 3.6068)
			(drill
				(offset 0 -0.381)
			)
			(layers "F.Cu" "F.Mask" "F.Paste")
			(net "HDD_PRSNT6")
		)
		(pad "A11" smd rect
			(at 1.500124 -0.309118 270)
			(size 0.7112 3.6068)
			(drill
				(offset 0 -0.381)
			)
			(layers "F.Cu" "F.Mask" "F.Paste")
			(net "HDD_PRSNT2")
		)
		(pad "A12" smd rect
			(at -1.500124 -0.309118 270)
			(size 0.7112 3.6068)
			(drill
				(offset 0 -0.381)
			)
			(layers "F.Cu" "F.Mask" "F.Paste")
			(net "HDD_PRSNT1")
		)
		(pad "A13" smd rect
			(at -2.500122 -0.309118 270)
			(size 0.7112 3.6068)
			(drill
				(offset 0 -0.381)
			)
			(layers "F.Cu" "F.Mask" "F.Paste")
			(net "HDD_PRSNT10")
		)
		(pad "A14" smd rect
			(at -3.50012 -0.309118 270)
			(size 0.7112 3.6068)
			(drill
				(offset 0 -0.381)
			)
			(layers "F.Cu" "F.Mask" "F.Paste")
			(net "HDD_PRSNT0")
		)
		(pad "A15" smd rect
			(at -4.500118 -0.309118 270)
			(size 0.7112 3.6068)
			(drill
				(offset 0 -0.381)
			)
			(layers "F.Cu" "F.Mask" "F.Paste")
			(net "HDD_PRSNT5")
		)
		(pad "A16" smd rect
			(at -5.500116 -0.309118 270)
			(size 0.7112 3.6068)
			(drill
				(offset 0 -0.381)
			)
			(layers "F.Cu" "F.Mask" "F.Paste")
			(net "SELF_TRAY_PRESENT")
		)
		(pad "A17" smd rect
			(at -6.500114 -0.309118 270)
			(size 0.7112 3.6068)
			(drill
				(offset 0 -0.381)
			)
			(layers "F.Cu" "F.Mask" "F.Paste")
			(net "PEER_TRAY_PRESENT")
		)
		(pad "A18" smd rect
			(at -7.500112 -0.309118 270)
			(size 0.7112 3.6068)
			(drill
				(offset 0 -0.381)
			)
			(layers "F.Cu" "F.Mask" "F.Paste")
			(net "EXP_A_PRNST_TX")
		)
		(pad "B1" smd rect
			(at 11.500104 -0.690118 270)
			(size 0.7112 3.6068)
			(layers "F.Cu" "F.Mask" "F.Paste")
			(net "SAS_EXP_A_PWR11")
		)
		(pad "B2" smd rect
			(at 10.500106 -0.690118 270)
			(size 0.7112 3.6068)
			(layers "F.Cu" "F.Mask" "F.Paste")
			(net "SAS_EXP_A_PWR12")
		)
		(pad "B3" smd rect
			(at 9.500108 -0.690118 270)
			(size 0.7112 3.6068)
			(layers "F.Cu" "F.Mask" "F.Paste")
			(net "SAS_EXP_A_PWR13")
		)
		(pad "B4" smd rect
			(at 8.50011 -0.690118 270)
			(size 0.7112 3.6068)
			(layers "F.Cu" "F.Mask" "F.Paste")
			(net "SAS_EXP_A_PWR14")
		)
		(pad "B5" smd rect
			(at 7.500112 -0.690118 270)
			(size 0.7112 3.6068)
			(layers "F.Cu" "F.Mask" "F.Paste")
			(net "SAS_EXP_A_PWR9")
		)
		(pad "B6" smd rect
			(at 6.500114 -0.690118 270)
			(size 0.7112 3.6068)
			(layers "F.Cu" "F.Mask" "F.Paste")
			(net "SAS_EXP_A_PWR8")
		)
		(pad "B7" smd rect
			(at 5.500116 -0.690118 270)
			(size 0.7112 3.6068)
			(layers "F.Cu" "F.Mask" "F.Paste")
			(net "SAS_EXP_A_PWR7")
		)
		(pad "B8" smd rect
			(at 4.500118 -0.690118 270)
			(size 0.7112 3.6068)
			(layers "F.Cu" "F.Mask" "F.Paste")
			(net "SAS_EXP_A_PWR4")
		)
		(pad "B9" smd rect
			(at 3.50012 -0.690118 270)
			(size 0.7112 3.6068)
			(layers "F.Cu" "F.Mask" "F.Paste")
			(net "SAS_EXP_A_PWR3")
		)
		(pad "B10" smd rect
			(at 2.500122 -0.690118 270)
			(size 0.7112 3.6068)
			(layers "F.Cu" "F.Mask" "F.Paste")
			(net "SAS_EXP_A_PWR6")
		)
		(pad "B11" smd rect
			(at 1.500124 -0.690118 270)
			(size 0.7112 3.6068)
			(layers "F.Cu" "F.Mask" "F.Paste")
			(net "SAS_EXP_A_PWR2")
		)
		(pad "B12" smd rect
			(at -1.500124 -0.690118 270)
			(size 0.7112 3.6068)
			(layers "F.Cu" "F.Mask" "F.Paste")
			(net "SAS_EXP_A_PWR1")
		)
		(pad "B13" smd rect
			(at -2.500122 -0.690118 270)
			(size 0.7112 3.6068)
			(layers "F.Cu" "F.Mask" "F.Paste")
			(net "SAS_EXP_A_PWR10")
		)
		(pad "B14" smd rect
			(at -3.50012 -0.690118 270)
			(size 0.7112 3.6068)
			(layers "F.Cu" "F.Mask" "F.Paste")
			(net "SAS_EXP_A_PWR0")
		)
		(pad "B15" smd rect
			(at -4.500118 -0.690118 270)
			(size 0.7112 3.6068)
			(layers "F.Cu" "F.Mask" "F.Paste")
			(net "SAS_EXP_A_PWR5")
		)
		(pad "B16" smd rect
			(at -5.500116 -0.690118 270)
			(size 0.7112 3.6068)
			(layers "F.Cu" "F.Mask" "F.Paste")
			(net "SAS_EXP_A_PWR15")
		)
		(pad "B17" smd rect
			(at -6.500114 -0.690118 270)
			(size 0.7112 3.6068)
			(layers "F.Cu" "F.Mask" "F.Paste")
			(net "PCIE_MATED#_A")
		)
		(pad "B18" smd rect
			(at -7.500112 -0.690118 270)
			(size 0.7112 3.6068)
			(layers "F.Cu" "F.Mask" "F.Paste")
			(net "EXP_B_PRNST_RX")
		)
		(zone
			(layers "F.Cu" "B.Cu" "In1.Cu" "In2.Cu" "In3.Cu" "In4.Cu" "In5.Cu" "In6.Cu")
			(hatch none 0.5)
			(connect_pads
				(clearance 0)
			)
			(min_thickness 0.25)
			(keepout
				(tracks not_allowed)
				(vias allowed)
				(pads allowed)
				(copperpour not_allowed)
				(footprints allowed)
			)
			(placement
				(enabled no)
				(sheetname "")
			)
			(fill
				(thermal_gap 0.5)
				(thermal_bridge_width 0.5)
				(island_removal_mode 0)
			)
			(polygon
				(pts
					(arc
						(start 3.960622 -472.304872)
						(mid 1.039622 -472.304872)
						(end 3.960622 -472.304872)
					)
				)
			)
		)
		(zone
			(layers "F.Cu" "B.Cu" "In1.Cu" "In2.Cu" "In3.Cu" "In4.Cu" "In5.Cu" "In6.Cu")
			(hatch none 0.5)
			(connect_pads
				(clearance 0)
			)
			(min_thickness 0.25)
			(keepout
				(tracks not_allowed)
				(vias allowed)
				(pads allowed)
				(copperpour not_allowed)
				(footprints allowed)
			)
			(placement
				(enabled no)
				(sheetname "")
			)
			(fill
				(thermal_gap 0.5)
				(thermal_bridge_width 0.5)
				(island_removal_mode 0)
			)
			(polygon
				(pts
					(arc
						(start 3.960622 -443.704726)
						(mid 1.039622 -443.704726)
						(end 3.960622 -443.704726)
					)
				)
			)
		)
	)
	(footprint ""
		(layer "F.Cu")
		(at 28.320746 -314.734702)
		(property "Reference" "C290"
			(at 0 0 0)
			(layer "F.SilkS")
			(hide yes)
			(effects
				(font
					(size 1.27 1.27)
				)
			)
		)
		(property "Value" "SC10U25V6KX-1GP"
			(at -0.0762 -5.1308 0)
			(unlocked yes)
			(layer "F.Fab")
			(hide yes)
			(effects
				(font
					(size 1.016 1.016)
					(thickness 0.1524)
				)
			)
		)
		(property "Device Type" "C1206H71"
			(at -0.127 -6.6548 0)
			(unlocked yes)
			(layer "F.Fab")
			(hide yes)
			(effects
				(font
					(size 1.016 1.016)
					(thickness 0.1524)
				)
			)
		)
		(duplicate_pad_numbers_are_jumpers no)
		(fp_line
			(start -1.016 -2.2352)
			(end 1.016 -2.2352)
			(stroke
				(width 0.1524)
				(type default)
			)
			(layer "F.SilkS")
		)
		(fp_line
			(start -1.016 -0.8382)
			(end -1.016 -2.2352)
			(stroke
				(width 0.1524)
				(type default)
			)
			(layer "F.SilkS")
		)
		(fp_line
			(start -1.016 2.2352)
			(end -1.016 0.8382)
			(stroke
				(width 0.1524)
				(type default)
			)
			(layer "F.SilkS")
		)
		(fp_line
			(start 1.016 -2.2352)
			(end 1.016 -0.8382)
			(stroke
				(width 0.1524)
				(type default)
			)
			(layer "F.SilkS")
		)
		(fp_line
			(start 1.016 0.8382)
			(end 1.016 2.2352)
			(stroke
				(width 0.1524)
				(type default)
			)
			(layer "F.SilkS")
		)
		(fp_line
			(start 1.016 2.2352)
			(end -1.016 2.2352)
			(stroke
				(width 0.1524)
				(type default)
			)
			(layer "F.SilkS")
		)
		(fp_rect
			(start -1.0922 2.3114)
			(end 1.0922 -2.3114)
			(stroke
				(width 0)
				(type default)
			)
			(fill no)
			(layer "F.CrtYd")
		)
		(fp_poly
			(pts
				(xy 1.0922 -2.3114) (xy 1.0922 2.3114) (xy -1.0922 2.3114) (xy -1.0922 -2.3114)
			)
			(stroke
				(width 0)
				(type default)
			)
			(fill no)
			(layer "F.Fab")
		)
		(pad "1" smd rect
			(at 0 -1.397)
			(size 1.651 1.27)
			(layers "F.Cu" "F.Mask" "F.Paste")
			(net "P12V_HDD11")
		)
		(pad "2" smd rect
			(at 0 1.397)
			(size 1.651 1.27)
			(layers "F.Cu" "F.Mask" "F.Paste")
			(net "GND")
		)
	)
	(footprint ""
		(layer "F.Cu")
		(at 45.338746 -144.2847 90)
		(property "Reference" "R214"
			(at 0 0 90)
			(layer "F.SilkS")
			(hide yes)
			(effects
				(font
					(size 1.27 1.27)
				)
			)
		)
		(property "Value" "0R2J-2-GP"
			(at 0.064008 -3.993896 90)
			(unlocked yes)
			(layer "F.Fab")
			(hide yes)
			(effects
				(font
					(size 1.016 1.016)
					(thickness 0.1524)
				)
			)
		)
		(property "Device Type" "R402H16"
			(at 0.064008 -5.517896 90)
			(unlocked yes)
			(layer "F.Fab")
			(hide yes)
			(effects
				(font
					(size 1.016 1.016)
					(thickness 0.1524)
				)
			)
		)
		(duplicate_pad_numbers_are_jumpers no)
		(fp_line
			(start 0.508 -0.9398)
			(end -0.508 -0.9398)
			(stroke
				(width 0.1524)
				(type default)
			)
			(layer "F.SilkS")
		)
		(fp_line
			(start -0.508 -0.9398)
			(end -0.508 0.9398)
			(stroke
				(width 0.1524)
				(type default)
			)
			(layer "F.SilkS")
		)
		(fp_rect
			(start -0.508 0.9398)
			(end 0.508 -0.9398)
			(stroke
				(width 0)
				(type default)
			)
			(fill no)
			(layer "F.CrtYd")
		)
		(fp_rect
			(start -0.508 0.9398)
			(end 0.508 -0.9398)
			(stroke
				(width 0)
				(type default)
			)
			(fill no)
			(layer "F.Fab")
		)
		(pad "1" smd custom
			(at 0 -0.4445 90)
			(size 0.1397 0.1397)
			(layers "F.Cu" "F.Mask" "F.Paste")
			(net "DRV_ACT_NET8")
			(options
				(clearance outline)
				(anchor circle)
			)
			(primitives
				(gr_poly
					(pts
						(arc
							(start -0.1778 -0.2794)
							(mid -0.249642 -0.249642)
							(end -0.2794 -0.1778)
						)
						(arc
							(start -0.2794 0.1778)
							(mid -0.249642 0.249642)
							(end -0.1778 0.2794)
						)
						(arc
							(start 0.1778 0.2794)
							(mid 0.249642 0.249642)
							(end 0.2794 0.1778)
						)
						(arc
							(start 0.2794 -0.1778)
							(mid 0.249642 -0.249642)
							(end 0.1778 -0.2794)
						)
					)
					(width 0)
					(fill yes)
				)
			)
		)
		(pad "2" smd custom
			(at 0 0.4445 90)
			(size 0.1397 0.1397)
			(layers "F.Cu" "F.Mask" "F.Paste")
			(net "DRIVE_ACT_8")
			(options
				(clearance outline)
				(anchor circle)
			)
			(primitives
				(gr_poly
					(pts
						(arc
							(start -0.1778 -0.2794)
							(mid -0.249642 -0.249642)
							(end -0.2794 -0.1778)
						)
						(arc
							(start -0.2794 0.1778)
							(mid -0.249642 0.249642)
							(end -0.1778 0.2794)
						)
						(arc
							(start 0.1778 0.2794)
							(mid 0.249642 0.249642)
							(end 0.2794 0.1778)
						)
						(arc
							(start 0.2794 -0.1778)
							(mid 0.249642 -0.249642)
							(end 0.1778 -0.2794)
						)
					)
					(width 0)
					(fill yes)
				)
			)
		)
	)
)
